# BASEBOARD_FAB2 (Tioga Pass) — schematic netlist excerpt (pin names and nets, part order shuffled) for the footprints in the layout excerpt that follows; sources: Cadence DE-HDL packaged netlist, KiCad conversion of Wiwynn_Tioga_Pass_MB.brd

R9F5  RES  3.32K 1% CHIP  pkg 0402  page 139 : A = P3V3_STBY ; B = PU_SPRV_LAN_PWR_GOOD
R25W182  RES  0.0 5% CHIP  pkg 0402  page 144 : A = XDP_SYSPWROK ; B = PWRGD_SYS_PWROK
R7C1  RES  200K 0.1% CHIP  pkg 0603  page 114 : A = XTAL_PCH_48M_IN ; B = XTAL_PCH_48M_OUT

(kicad_pcb
	(version 20260206)
	(generator "pcbnew")
	(generator_version "10.0")
	(general
		(thickness 1.6)
		(legacy_teardrops no)
	)
	(paper "A4")
	(title_block
		(title "Wiwynn_Tioga_Pass_MB.brd")
		(comment 1 "Tioga Pass / footprints 1443-1445 of 4770")
	)
	(layers
		(0 "F.Cu" signal "TOP")
		(4 "In1.Cu" signal "L2GND")
		(6 "In2.Cu" signal "L3")
		(8 "In3.Cu" signal "L4GND")
		(10 "In4.Cu" signal "L5")
		(12 "In5.Cu" signal "L6GND")
		(14 "In6.Cu" signal "L7VCC")
		(16 "In7.Cu" signal "L8VCC")
		(18 "In8.Cu" signal "L9GND")
		(20 "In9.Cu" signal "L10")
		(22 "In10.Cu" signal "L11GND")
		(24 "In11.Cu" signal "L12")
		(26 "In12.Cu" signal "L13GND")
		(2 "B.Cu" signal "BOTTOM")
		(9 "F.Adhes" user "F.Adhesive")
		(11 "B.Adhes" user "B.Adhesive")
		(13 "F.Paste" user "Package Geometry/Pastemask Top")
		(15 "B.Paste" user "Package Geometry/Pastemask Bottom")
		(5 "F.SilkS" user "Ref Des/Silkscreen Top")
		(7 "B.SilkS" user "Ref Des/Silkscreen Bottom")
		(1 "F.Mask" user "Board Geometry/Soldermask Top")
		(3 "B.Mask" user "Board Geometry/Soldermask Bottom")
		(17 "Dwgs.User" user "User.Drawings")
		(19 "Cmts.User" user "User.Comments")
		(21 "Eco1.User" user "User.Eco1")
		(23 "Eco2.User" user "User.Eco2")
		(25 "Edge.Cuts" user "Board Geometry/Outline")
		(27 "Margin" user)
		(31 "F.CrtYd" user "Package Geometry/Place Bound Top")
		(29 "B.CrtYd" user "Package Geometry/Place Bound Bottom")
		(35 "F.Fab" user "Ref Des/Assembly Top")
		(33 "B.Fab" user "Ref Des/Assembly Bottom")
	)
	(footprint ""
		(layer "F.Cu")
		(at 491.49 -39.0144 -90)
		(property "Reference" "R9F5"
			(at 0 0 270)
			(layer "F.SilkS")
			(hide yes)
			(effects
				(font
					(size 1.27 1.27)
				)
			)
		)
		(property "Value" ""
			(at 0 0 270)
			(layer "F.Fab")
			(effects
				(font
					(size 1.27 1.27)
				)
			)
		)
		(duplicate_pad_numbers_are_jumpers no)
		(fp_poly
			(pts
				(xy -0.2794 -0.1016) (xy 0.2794 -0.1016) (xy 0.2794 0.9906) (xy -0.2794 0.9906)
			)
			(stroke
				(width 0)
				(type default)
			)
			(fill no)
			(layer "F.CrtYd")
		)
		(fp_line
			(start -0.2794 0.9906)
			(end 0.2794 0.9906)
			(stroke
				(width 0.1)
				(type default)
			)
			(layer "F.Fab")
		)
		(fp_line
			(start 0.2794 0.9906)
			(end 0.2794 -0.1016)
			(stroke
				(width 0.1)
				(type default)
			)
			(layer "F.Fab")
		)
		(fp_line
			(start -0.2794 -0.1016)
			(end -0.2794 0.9906)
			(stroke
				(width 0.1)
				(type default)
			)
			(layer "F.Fab")
		)
		(fp_line
			(start 0.2794 -0.1016)
			(end -0.2794 -0.1016)
			(stroke
				(width 0.1)
				(type default)
			)
			(layer "F.Fab")
		)
		(pad "1" smd rect
			(at 0 0 270)
			(size 0.508 0.508)
			(layers "F.Cu" "F.Mask" "F.Paste")
			(net "P3V3_STBY")
		)
		(pad "2" smd rect
			(at 0 0.889 270)
			(size 0.508 0.508)
			(layers "F.Cu" "F.Mask" "F.Paste")
			(net "PU_SPRV_LAN_PWR_GOOD")
		)
		(zone
			(layer "F.Cu")
			(hatch none 0.5)
			(connect_pads
				(clearance 0)
			)
			(min_thickness 0.25)
			(keepout
				(tracks not_allowed)
				(vias allowed)
				(pads allowed)
				(copperpour not_allowed)
				(footprints allowed)
			)
			(placement
				(enabled no)
				(sheetname "")
			)
			(fill
				(thermal_gap 0.5)
				(thermal_bridge_width 0.5)
				(island_removal_mode 0)
			)
			(polygon
				(pts
					(xy 490.855 -39.2684) (xy 490.855 -38.7604) (xy 491.236 -38.7604) (xy 491.236 -39.2684)
				)
			)
		)
		(zone
			(layer "F.Cu")
			(hatch none 0.5)
			(connect_pads
				(clearance 0)
			)
			(min_thickness 0.25)
			(keepout
				(tracks allowed)
				(vias not_allowed)
				(pads allowed)
				(copperpour not_allowed)
				(footprints allowed)
			)
			(placement
				(enabled no)
				(sheetname "")
			)
			(fill
				(thermal_gap 0.5)
				(thermal_bridge_width 0.5)
				(island_removal_mode 0)
			)
			(polygon
				(pts
					(xy 491.236 -39.2684) (xy 491.236 -38.7604) (xy 490.855 -38.7604) (xy 490.855 -39.2684)
				)
			)
		)
	)
	(footprint ""
		(layer "F.Cu")
		(at 369.7224 -108.6104)
		(property "Reference" "R7C1"
			(at 0 0 0)
			(layer "F.SilkS")
			(hide yes)
			(effects
				(font
					(size 1.27 1.27)
				)
			)
		)
		(property "Value" ""
			(at 0 0 0)
			(layer "F.Fab")
			(effects
				(font
					(size 1.27 1.27)
				)
			)
		)
		(duplicate_pad_numbers_are_jumpers no)
		(fp_poly
			(pts
				(xy -0.4953 -0.2032) (xy 0.4953 -0.2032) (xy 0.4953 1.6002) (xy -0.4953 1.6002)
			)
			(stroke
				(width 0)
				(type default)
			)
			(fill no)
			(layer "F.CrtYd")
		)
		(fp_line
			(start -0.4953 -0.2032)
			(end 0.4953 -0.2032)
			(stroke
				(width 0.1)
				(type default)
			)
			(layer "F.Fab")
		)
		(fp_line
			(start -0.4953 1.6002)
			(end -0.4953 -0.2032)
			(stroke
				(width 0.1)
				(type default)
			)
			(layer "F.Fab")
		)
		(fp_line
			(start 0.4953 -0.2032)
			(end 0.4953 1.6002)
			(stroke
				(width 0.1)
				(type default)
			)
			(layer "F.Fab")
		)
		(fp_line
			(start 0.4953 1.6002)
			(end -0.4953 1.6002)
			(stroke
				(width 0.1)
				(type default)
			)
			(layer "F.Fab")
		)
		(pad "1" smd rect
			(at 0 0)
			(size 0.762 0.889)
			(layers "F.Cu" "F.Mask" "F.Paste")
			(net "XTAL_PCH_48M_IN")
		)
		(pad "2" smd rect
			(at 0 1.397)
			(size 0.762 0.889)
			(layers "F.Cu" "F.Mask" "F.Paste")
			(net "XTAL_PCH_48M_OUT")
		)
		(zone
			(layer "F.Cu")
			(hatch none 0.5)
			(connect_pads
				(clearance 0)
			)
			(min_thickness 0.25)
			(keepout
				(tracks not_allowed)
				(vias allowed)
				(pads allowed)
				(copperpour not_allowed)
				(footprints allowed)
			)
			(placement
				(enabled no)
				(sheetname "")
			)
			(fill
				(thermal_gap 0.5)
				(thermal_bridge_width 0.5)
				(island_removal_mode 0)
			)
			(polygon
				(pts
					(xy 369.3414 -107.6579) (xy 370.1034 -107.6579) (xy 370.1034 -108.1659) (xy 369.3414 -108.1659)
				)
			)
		)
		(zone
			(layer "F.Cu")
			(hatch none 0.5)
			(connect_pads
				(clearance 0)
			)
			(min_thickness 0.25)
			(keepout
				(tracks allowed)
				(vias not_allowed)
				(pads allowed)
				(copperpour not_allowed)
				(footprints allowed)
			)
			(placement
				(enabled no)
				(sheetname "")
			)
			(fill
				(thermal_gap 0.5)
				(thermal_bridge_width 0.5)
				(island_removal_mode 0)
			)
			(polygon
				(pts
					(xy 370.1034 -107.6579) (xy 370.1034 -108.1659) (xy 369.3414 -108.1659) (xy 369.3414 -107.6579)
				)
			)
		)
	)
	(footprint ""
		(layer "F.Cu")
		(at 394.462 -41.3766)
		(property "Reference" "R25W182"
			(at -0.8382 -0.67818 0)
			(unlocked yes)
			(layer "F.SilkS")
			(effects
				(font
					(size 0.4064 0.254)
					(thickness 0.1524)
				)
				(justify left)
			)
		)
		(property "Value" ""
			(at 0 0 0)
			(layer "F.Fab")
			(effects
				(font
					(size 1.27 1.27)
				)
			)
		)
		(duplicate_pad_numbers_are_jumpers no)
		(fp_poly
			(pts
				(xy -0.2794 -0.1016) (xy 0.2794 -0.1016) (xy 0.2794 0.9906) (xy -0.2794 0.9906)
			)
			(stroke
				(width 0)
				(type default)
			)
			(fill no)
			(layer "F.CrtYd")
		)
		(fp_line
			(start -0.2794 -0.1016)
			(end -0.2794 0.9906)
			(stroke
				(width 0.1)
				(type default)
			)
			(layer "F.Fab")
		)
		(fp_line
			(start -0.2794 0.9906)
			(end 0.2794 0.9906)
			(stroke
				(width 0.1)
				(type default)
			)
			(layer "F.Fab")
		)
		(fp_line
			(start 0.2794 -0.1016)
			(end -0.2794 -0.1016)
			(stroke
				(width 0.1)
				(type default)
			)
			(layer "F.Fab")
		)
		(fp_line
			(start 0.2794 0.9906)
			(end 0.2794 -0.1016)
			(stroke
				(width 0.1)
				(type default)
			)
			(layer "F.Fab")
		)
		(pad "1" smd rect
			(at 0 0)
			(size 0.508 0.508)
			(layers "F.Cu" "F.Mask" "F.Paste")
			(net "XDP_SYSPWROK")
		)
		(pad "2" smd rect
			(at 0 0.889)
			(size 0.508 0.508)
			(layers "F.Cu" "F.Mask" "F.Paste")
			(net "PWRGD_SYS_PWROK")
		)
		(zone
			(layer "F.Cu")
			(hatch none 0.5)
			(connect_pads
				(clearance 0)
			)
			(min_thickness 0.25)
			(keepout
				(tracks allowed)
				(vias not_allowed)
				(pads allowed)
				(copperpour not_allowed)
				(footprints allowed)
			)
			(placement
				(enabled no)
				(sheetname "")
			)
			(fill
				(thermal_gap 0.5)
				(thermal_bridge_width 0.5)
				(island_removal_mode 0)
			)
			(polygon
				(pts
					(xy 394.208 -41.1226) (xy 394.716 -41.1226) (xy 394.716 -40.7416) (xy 394.208 -40.7416)
				)
			)
		)
		(zone
			(layer "F.Cu")
			(hatch none 0.5)
			(connect_pads
				(clearance 0)
			)
			(min_thickness 0.25)
			(keepout
				(tracks not_allowed)
				(vias allowed)
				(pads allowed)
				(copperpour not_allowed)
				(footprints allowed)
			)
			(placement
				(enabled no)
				(sheetname "")
			)
			(fill
				(thermal_gap 0.5)
				(thermal_bridge_width 0.5)
				(island_removal_mode 0)
			)
			(polygon
				(pts
					(xy 394.208 -40.7416) (xy 394.716 -40.7416) (xy 394.716 -41.1226) (xy 394.208 -41.1226)
				)
			)
		)
	)
)
